(kicad_pcb
	(version 20260206)
	(generator "pcbnew")
	(generator_version "10.0")
	(general
		(thickness 1.6)
		(legacy_teardrops no)
	)
	(paper "A4")
	(title_block
		(title "03242023_DA0F0TMBIJ0_F0T_Motherboard_J_brd_V01_OCP.brd")
		(comment 1 "Grand Teton / footprints 2788-2795 of 6105")
	)
	(layers
		(0 "F.Cu" signal "TOP")
		(4 "In1.Cu" signal "GND")
		(6 "In2.Cu" signal "IN1")
		(8 "In3.Cu" signal "GND1")
		(10 "In4.Cu" signal "IN2")
		(12 "In5.Cu" signal "GND2")
		(14 "In6.Cu" signal "IN3")
		(16 "In7.Cu" signal "GND3")
		(18 "In8.Cu" signal "VCC")
		(20 "In9.Cu" signal "VCC1")
		(22 "In10.Cu" signal "GND4")
		(24 "In11.Cu" signal "IN4")
		(26 "In12.Cu" signal "GND5")
		(28 "In13.Cu" signal "IN5")
		(30 "In14.Cu" signal "GND6")
		(32 "In15.Cu" signal "IN6")
		(34 "In16.Cu" signal "GND7")
		(2 "B.Cu" signal "BOTTOM")
		(9 "F.Adhes" user "F.Adhesive")
		(11 "B.Adhes" user "B.Adhesive")
		(13 "F.Paste" user "Package Geometry/Pastemask Top")
		(15 "B.Paste" user "Package Geometry/Pastemask Bottom")
		(5 "F.SilkS" user "Ref Des/Silkscreen Top")
		(7 "B.SilkS" user "Ref Des/Silkscreen Bottom")
		(1 "F.Mask" user "Board Geometry/Soldermask Top")
		(3 "B.Mask" user "Board Geometry/Soldermask Bottom")
		(17 "Dwgs.User" user "User.Drawings")
		(19 "Cmts.User" user "User.Comments")
		(21 "Eco1.User" user "User.Eco1")
		(23 "Eco2.User" user "User.Eco2")
		(25 "Edge.Cuts" user "Board Geometry/Outline")
		(27 "Margin" user)
		(31 "F.CrtYd" user "Package Geometry/Place Bound Top")
		(29 "B.CrtYd" user "Package Geometry/Place Bound Bottom")
		(35 "F.Fab" user "Ref Des/Assembly Top")
		(33 "B.Fab" user "Ref Des/Assembly Bottom")
	)
	(footprint ""
		(layer "F.Cu")
		(at 94.045278 -102.509574 180)
		(property "Reference" "Q105"
			(at 3.089656 0.763016 0)
			(unlocked yes)
			(layer "F.SilkS")
			(effects
				(font
					(size 0.7874 0.5842)
					(thickness 0.1524)
				)
			)
		)
		(property "Value" ""
			(at 0 0 180)
			(layer "F.Fab")
			(effects
				(font
					(size 1.27 1.27)
				)
			)
		)
		(duplicate_pad_numbers_are_jumpers no)
		(fp_line
			(start 1.376172 1.199896)
			(end -1.376172 1.199896)
			(stroke
				(width 0.1524)
				(type default)
			)
			(layer "F.SilkS")
		)
		(fp_line
			(start 1.376172 -1.199896)
			(end 1.376172 1.199896)
			(stroke
				(width 0.1524)
				(type default)
			)
			(layer "F.SilkS")
		)
		(fp_line
			(start 0.508 -1.199896)
			(end 1.376172 -1.199896)
			(stroke
				(width 0.1524)
				(type default)
			)
			(layer "F.SilkS")
		)
		(fp_line
			(start 0 -0.762)
			(end 0.508 -1.199896)
			(stroke
				(width 0.1524)
				(type default)
			)
			(layer "F.SilkS")
		)
		(fp_line
			(start -0.508 -1.199896)
			(end 0 -0.762)
			(stroke
				(width 0.1524)
				(type default)
			)
			(layer "F.SilkS")
		)
		(fp_line
			(start -1.376172 1.199896)
			(end -1.376172 -1.199896)
			(stroke
				(width 0.1524)
				(type default)
			)
			(layer "F.SilkS")
		)
		(fp_line
			(start -1.376172 -1.199896)
			(end -0.508 -1.199896)
			(stroke
				(width 0.1524)
				(type default)
			)
			(layer "F.SilkS")
		)
		(fp_poly
			(pts
				(xy -1.4605 -0.7493) (xy -2.2225 -0.3683) (xy -2.2225 -1.1303)
			)
			(stroke
				(width 0)
				(type default)
			)
			(fill yes)
			(layer "F.SilkS")
		)
		(fp_line
			(start 0.674878 1.100074)
			(end -0.674878 1.100074)
			(stroke
				(width 0.1)
				(type default)
			)
			(layer "F.Fab")
		)
		(fp_line
			(start 0.674878 -1.100074)
			(end 0.674878 1.100074)
			(stroke
				(width 0.1)
				(type default)
			)
			(layer "F.Fab")
		)
		(fp_line
			(start -0.674878 1.100074)
			(end -0.674878 -1.100074)
			(stroke
				(width 0.1)
				(type default)
			)
			(layer "F.Fab")
		)
		(fp_line
			(start -0.674878 -1.100074)
			(end 0.674878 -1.100074)
			(stroke
				(width 0.1)
				(type default)
			)
			(layer "F.Fab")
		)
		(fp_poly
			(pts
				(xy -1.4605 -0.7493) (xy -2.2225 -1.1303) (xy -2.2225 -0.3683)
			)
			(stroke
				(width 0)
				(type default)
			)
			(fill yes)
			(layer "F.Fab")
		)
		(pad "1" smd rect
			(at -0.899922 -0.750062 90)
			(size 0.6096 0.6096)
			(layers "F.Cu" "F.Mask" "F.Paste")
			(net "GND")
		)
		(pad "2" smd rect
			(at -0.899922 0 90)
			(size 0.4064 0.6096)
			(layers "F.Cu" "F.Mask" "F.Paste")
			(net "RST_PLD_CPU1_DRAM_AB_N")
		)
		(pad "3" smd rect
			(at -0.899922 0.750062 90)
			(size 0.6096 0.6096)
			(layers "F.Cu" "F.Mask" "F.Paste")
			(net "Net_1467")
		)
		(pad "4" smd rect
			(at 0.899922 0.750062 90)
			(size 0.6096 0.6096)
			(layers "F.Cu" "F.Mask" "F.Paste")
			(net "Net_1469")
		)
		(pad "5" smd rect
			(at 0.899922 0 90)
			(size 0.4064 0.6096)
			(layers "F.Cu" "F.Mask" "F.Paste")
			(net "Net_1468")
		)
		(pad "6" smd rect
			(at 0.899922 -0.750062 90)
			(size 0.6096 0.6096)
			(layers "F.Cu" "F.Mask" "F.Paste")
			(net "LED_RST_PLD_CPU1_DRAM_AB_N_D")
		)
	)
	(footprint ""
		(layer "F.Cu")
		(at 56.349138 -362.656882)
		(property "Reference" "PC1678"
			(at 0 0 0)
			(layer "F.SilkS")
			(hide yes)
			(effects
				(font
					(size 1.27 1.27)
				)
			)
		)
		(property "Value" ""
			(at 0 0 0)
			(layer "F.Fab")
			(effects
				(font
					(size 1.27 1.27)
				)
			)
		)
		(duplicate_pad_numbers_are_jumpers no)
		(fp_line
			(start -1.524 -0.762)
			(end 1.524 -0.762)
			(stroke
				(width 0.1524)
				(type default)
			)
			(layer "F.SilkS")
		)
		(fp_line
			(start -1.524 0.762)
			(end -1.524 -0.762)
			(stroke
				(width 0.1524)
				(type default)
			)
			(layer "F.SilkS")
		)
		(fp_line
			(start 1.524 -0.762)
			(end 1.524 0.762)
			(stroke
				(width 0.1524)
				(type default)
			)
			(layer "F.SilkS")
		)
		(fp_line
			(start 1.524 0.762)
			(end -1.524 0.762)
			(stroke
				(width 0.1524)
				(type default)
			)
			(layer "F.SilkS")
		)
		(fp_line
			(start -1.1049 -0.724916)
			(end -1.1049 0.724916)
			(stroke
				(width 0.1)
				(type default)
			)
			(layer "F.Fab")
		)
		(fp_line
			(start -1.1049 0.724916)
			(end 1.1049 0.724916)
			(stroke
				(width 0.1)
				(type default)
			)
			(layer "F.Fab")
		)
		(fp_line
			(start 1.1049 -0.724916)
			(end -1.1049 -0.724916)
			(stroke
				(width 0.1)
				(type default)
			)
			(layer "F.Fab")
		)
		(fp_line
			(start 1.1049 0.724916)
			(end 1.1049 -0.724916)
			(stroke
				(width 0.1)
				(type default)
			)
			(layer "F.Fab")
		)
		(pad "1" smd rect
			(at -0.889 0 180)
			(size 1.016 1.27)
			(layers "F.Cu" "F.Mask" "F.Paste")
			(net "SW_P12V_PVCCFA_EHV_FIVRA_CPU1_L")
		)
		(pad "2" smd rect
			(at 0.889 0 180)
			(size 1.016 1.27)
			(layers "F.Cu" "F.Mask" "F.Paste")
			(net "GND")
		)
	)
	(footprint ""
		(layer "F.Cu")
		(at 167.899842 -160.50006)
		(property "Reference" "H86"
			(at -5.718302 -4.55549 0)
			(unlocked yes)
			(layer "F.SilkS")
			(effects
				(font
					(size 0.7874 0.5842)
					(thickness 0.1524)
				)
				(justify left)
			)
		)
		(property "Value" ""
			(at 0 0 0)
			(layer "F.Fab")
			(effects
				(font
					(size 1.27 1.27)
				)
			)
		)
		(duplicate_pad_numbers_are_jumpers no)
		(pad "1" thru_hole circle
			(at 0 0)
			(size 10.0076 10.0076)
			(drill 5.6134)
			(layers "*.Cu" "*.Mask")
			(remove_unused_layers no)
			(net "GND")
			(clearance -1.9431)
		)
	)
	(footprint ""
		(layer "F.Cu")
		(at 199.4916 -93.98 -90)
		(property "Reference" "U337"
			(at -2.159 0.701548 90)
			(unlocked yes)
			(layer "F.SilkS")
			(effects
				(font
					(size 0.7874 0.5842)
					(thickness 0.1524)
				)
				(justify left)
			)
		)
		(property "Value" ""
			(at 0 0 270)
			(layer "F.Fab")
			(effects
				(font
					(size 1.27 1.27)
				)
			)
		)
		(duplicate_pad_numbers_are_jumpers no)
		(fp_line
			(start -1.868424 1.519936)
			(end 1.868424 1.519936)
			(stroke
				(width 0.1524)
				(type default)
			)
			(layer "F.SilkS")
		)
		(fp_line
			(start 1.868424 1.519936)
			(end 1.868424 -1.519936)
			(stroke
				(width 0.1524)
				(type default)
			)
			(layer "F.SilkS")
		)
		(fp_line
			(start -1.868424 -1.519936)
			(end -1.868424 1.519936)
			(stroke
				(width 0.1524)
				(type default)
			)
			(layer "F.SilkS")
		)
		(fp_line
			(start 1.868424 -1.519936)
			(end -1.868424 -1.519936)
			(stroke
				(width 0.1524)
				(type default)
			)
			(layer "F.SilkS")
		)
		(fp_line
			(start -0.700024 1.519936)
			(end 0.700024 1.519936)
			(stroke
				(width 0.1)
				(type default)
			)
			(layer "F.Fab")
		)
		(fp_line
			(start 0.700024 1.519936)
			(end 0.700024 -1.519936)
			(stroke
				(width 0.1)
				(type default)
			)
			(layer "F.Fab")
		)
		(fp_line
			(start -0.700024 -1.519936)
			(end -0.700024 1.519936)
			(stroke
				(width 0.1)
				(type default)
			)
			(layer "F.Fab")
		)
		(fp_line
			(start 0.700024 -1.519936)
			(end -0.700024 -1.519936)
			(stroke
				(width 0.1)
				(type default)
			)
			(layer "F.Fab")
		)
		(pad "1" smd rect
			(at -1.18491 -0.94996 180)
			(size 0.6096 1.0668)
			(layers "F.Cu" "F.Mask" "F.Paste")
			(net "UV_ADR_P2V5_COMP")
		)
		(pad "2" smd rect
			(at -1.18491 0.94996 180)
			(size 0.6096 1.0668)
			(layers "F.Cu" "F.Mask" "F.Paste")
			(net "GND")
		)
		(pad "3" smd rect
			(at 1.18491 0 180)
			(size 0.6096 1.0668)
			(layers "F.Cu" "F.Mask" "F.Paste")
			(net "Net_8628")
		)
	)
	(footprint ""
		(layer "F.Cu")
		(at 27.598878 -16.099536 90)
		(property "Reference" "C814"
			(at 0 0 90)
			(layer "F.SilkS")
			(hide yes)
			(effects
				(font
					(size 1.27 1.27)
				)
			)
		)
		(property "Value" ""
			(at 0 0 90)
			(layer "F.Fab")
			(effects
				(font
					(size 1.27 1.27)
				)
			)
		)
		(duplicate_pad_numbers_are_jumpers no)
		(fp_line
			(start 0.299974 -0.150114)
			(end 0.299974 0.150114)
			(stroke
				(width 0.1)
				(type default)
			)
			(layer "F.Fab")
		)
		(fp_line
			(start -0.299974 -0.150114)
			(end 0.299974 -0.150114)
			(stroke
				(width 0.1)
				(type default)
			)
			(layer "F.Fab")
		)
		(fp_line
			(start 0.299974 0.150114)
			(end -0.299974 0.150114)
			(stroke
				(width 0.1)
				(type default)
			)
			(layer "F.Fab")
		)
		(fp_line
			(start -0.299974 0.150114)
			(end -0.299974 -0.150114)
			(stroke
				(width 0.1)
				(type default)
			)
			(layer "F.Fab")
		)
		(pad "1" smd rect
			(at -0.2667 0 90)
			(size 0.3048 0.381)
			(layers "F.Cu" "F.Mask" "F.Paste")
			(net "P5E_CPU1_PE1_TX_C_DN<11>")
		)
		(pad "2" smd rect
			(at 0.2667 0 90)
			(size 0.3048 0.381)
			(layers "F.Cu" "F.Mask" "F.Paste")
			(net "P5E_CPU1_PE1_TX_DN<11>")
		)
	)
	(footprint ""
		(layer "F.Cu")
		(at 315.405008 -408.517344 -90)
		(property "Reference" "C909"
			(at 0 0 270)
			(layer "F.SilkS")
			(hide yes)
			(effects
				(font
					(size 1.27 1.27)
				)
			)
		)
		(property "Value" ""
			(at 0 0 270)
			(layer "F.Fab")
			(effects
				(font
					(size 1.27 1.27)
				)
			)
		)
		(duplicate_pad_numbers_are_jumpers no)
		(fp_line
			(start -0.299974 0.150114)
			(end -0.299974 -0.150114)
			(stroke
				(width 0.1)
				(type default)
			)
			(layer "F.Fab")
		)
		(fp_line
			(start 0.299974 0.150114)
			(end -0.299974 0.150114)
			(stroke
				(width 0.1)
				(type default)
			)
			(layer "F.Fab")
		)
		(fp_line
			(start -0.299974 -0.150114)
			(end 0.299974 -0.150114)
			(stroke
				(width 0.1)
				(type default)
			)
			(layer "F.Fab")
		)
		(fp_line
			(start 0.299974 -0.150114)
			(end 0.299974 0.150114)
			(stroke
				(width 0.1)
				(type default)
			)
			(layer "F.Fab")
		)
		(pad "1" smd rect
			(at -0.2667 0 270)
			(size 0.3048 0.381)
			(layers "F.Cu" "F.Mask" "F.Paste")
			(net "P5E_CPU0_PE0_TX_C_DP<12>")
		)
		(pad "2" smd rect
			(at 0.2667 0 270)
			(size 0.3048 0.381)
			(layers "F.Cu" "F.Mask" "F.Paste")
			(net "P5E_CPU0_PE0_TX_DP<12>")
		)
	)
	(footprint ""
		(layer "F.Cu")
		(at 300.094904 -41.987724 -90)
		(property "Reference" "R1342"
			(at 0 0 270)
			(layer "F.SilkS")
			(hide yes)
			(effects
				(font
					(size 1.27 1.27)
				)
			)
		)
		(property "Value" ""
			(at 0 0 270)
			(layer "F.Fab")
			(effects
				(font
					(size 1.27 1.27)
				)
			)
		)
		(duplicate_pad_numbers_are_jumpers no)
		(fp_line
			(start -0.7874 0.4064)
			(end -0.7874 -0.4064)
			(stroke
				(width 0.1524)
				(type default)
			)
			(layer "F.SilkS")
		)
		(fp_line
			(start 0.7874 0.4064)
			(end -0.7874 0.4064)
			(stroke
				(width 0.1524)
				(type default)
			)
			(layer "F.SilkS")
		)
		(fp_line
			(start -0.7874 -0.4064)
			(end 0.7874 -0.4064)
			(stroke
				(width 0.1524)
				(type default)
			)
			(layer "F.SilkS")
		)
		(fp_line
			(start 0.7874 -0.4064)
			(end 0.7874 0.4064)
			(stroke
				(width 0.1524)
				(type default)
			)
			(layer "F.SilkS")
		)
		(fp_line
			(start -0.67945 0.3048)
			(end -0.67945 -0.305054)
			(stroke
				(width 0.1)
				(type default)
			)
			(layer "F.Fab")
		)
		(fp_line
			(start -0.12065 0.3048)
			(end -0.67945 0.3048)
			(stroke
				(width 0.1)
				(type default)
			)
			(layer "F.Fab")
		)
		(fp_line
			(start 0.120396 0.3048)
			(end 0.120396 0.2794)
			(stroke
				(width 0.1)
				(type default)
			)
			(layer "F.Fab")
		)
		(fp_line
			(start 0.67945 0.3048)
			(end 0.120396 0.3048)
			(stroke
				(width 0.1)
				(type default)
			)
			(layer "F.Fab")
		)
		(fp_line
			(start -0.12065 0.2794)
			(end -0.12065 0.3048)
			(stroke
				(width 0.1)
				(type default)
			)
			(layer "F.Fab")
		)
		(fp_line
			(start 0.120396 0.2794)
			(end -0.12065 0.2794)
			(stroke
				(width 0.1)
				(type default)
			)
			(layer "F.Fab")
		)
		(fp_line
			(start -0.12065 -0.2794)
			(end 0.12065 -0.2794)
			(stroke
				(width 0.1)
				(type default)
			)
			(layer "F.Fab")
		)
		(fp_line
			(start 0.12065 -0.2794)
			(end 0.12065 -0.3048)
			(stroke
				(width 0.1)
				(type default)
			)
			(layer "F.Fab")
		)
		(fp_line
			(start 0.12065 -0.3048)
			(end 0.67945 -0.3048)
			(stroke
				(width 0.1)
				(type default)
			)
			(layer "F.Fab")
		)
		(fp_line
			(start 0.67945 -0.3048)
			(end 0.67945 0.3048)
			(stroke
				(width 0.1)
				(type default)
			)
			(layer "F.Fab")
		)
		(fp_line
			(start -0.67945 -0.305054)
			(end -0.12065 -0.305054)
			(stroke
				(width 0.1)
				(type default)
			)
			(layer "F.Fab")
		)
		(fp_line
			(start -0.12065 -0.305054)
			(end -0.12065 -0.2794)
			(stroke
				(width 0.1)
				(type default)
			)
			(layer "F.Fab")
		)
		(pad "1" smd circle
			(at -0.40005 0 270)
			(size 0 0)
			(layers "F.Cu" "F.Mask" "F.Paste")
			(net "P1V05_PCH_AUX")
		)
		(pad "2" smd circle
			(at 0.40005 0 270)
			(size 0 0)
			(layers "F.Cu" "F.Mask" "F.Paste")
			(net "FM_ME_RCVR_N")
		)
	)
	(footprint ""
		(layer "F.Cu")
		(at 182.42788 -99.659948 -90)
		(property "Reference" "R1415"
			(at 0 0 270)
			(layer "F.SilkS")
			(hide yes)
			(effects
				(font
					(size 1.27 1.27)
				)
			)
		)
		(property "Value" ""
			(at 0 0 270)
			(layer "F.Fab")
			(effects
				(font
					(size 1.27 1.27)
				)
			)
		)
		(duplicate_pad_numbers_are_jumpers no)
		(fp_line
			(start -0.7874 0.4064)
			(end -0.7874 -0.4064)
			(stroke
				(width 0.1524)
				(type default)
			)
			(layer "F.SilkS")
		)
		(fp_line
			(start 0.7874 0.4064)
			(end -0.7874 0.4064)
			(stroke
				(width 0.1524)
				(type default)
			)
			(layer "F.SilkS")
		)
		(fp_line
			(start -0.7874 -0.4064)
			(end 0.7874 -0.4064)
			(stroke
				(width 0.1524)
				(type default)
			)
			(layer "F.SilkS")
		)
		(fp_line
			(start 0.7874 -0.4064)
			(end 0.7874 0.4064)
			(stroke
				(width 0.1524)
				(type default)
			)
			(layer "F.SilkS")
		)
		(fp_line
			(start -0.67945 0.3048)
			(end -0.67945 -0.305054)
			(stroke
				(width 0.1)
				(type default)
			)
			(layer "F.Fab")
		)
		(fp_line
			(start -0.12065 0.3048)
			(end -0.67945 0.3048)
			(stroke
				(width 0.1)
				(type default)
			)
			(layer "F.Fab")
		)
		(fp_line
			(start 0.120396 0.3048)
			(end 0.120396 0.2794)
			(stroke
				(width 0.1)
				(type default)
			)
			(layer "F.Fab")
		)
		(fp_line
			(start 0.67945 0.3048)
			(end 0.120396 0.3048)
			(stroke
				(width 0.1)
				(type default)
			)
			(layer "F.Fab")
		)
		(fp_line
			(start -0.12065 0.2794)
			(end -0.12065 0.3048)
			(stroke
				(width 0.1)
				(type default)
			)
			(layer "F.Fab")
		)
		(fp_line
			(start 0.120396 0.2794)
			(end -0.12065 0.2794)
			(stroke
				(width 0.1)
				(type default)
			)
			(layer "F.Fab")
		)
		(fp_line
			(start -0.12065 -0.2794)
			(end 0.12065 -0.2794)
			(stroke
				(width 0.1)
				(type default)
			)
			(layer "F.Fab")
		)
		(fp_line
			(start 0.12065 -0.2794)
			(end 0.12065 -0.3048)
			(stroke
				(width 0.1)
				(type default)
			)
			(layer "F.Fab")
		)
		(fp_line
			(start 0.12065 -0.3048)
			(end 0.67945 -0.3048)
			(stroke
				(width 0.1)
				(type default)
			)
			(layer "F.Fab")
		)
		(fp_line
			(start 0.67945 -0.3048)
			(end 0.67945 0.3048)
			(stroke
				(width 0.1)
				(type default)
			)
			(layer "F.Fab")
		)
		(fp_line
			(start -0.67945 -0.305054)
			(end -0.12065 -0.305054)
			(stroke
				(width 0.1)
				(type default)
			)
			(layer "F.Fab")
		)
		(fp_line
			(start -0.12065 -0.305054)
			(end -0.12065 -0.2794)
			(stroke
				(width 0.1)
				(type default)
			)
			(layer "F.Fab")
		)
		(pad "1" smd circle
			(at -0.40005 0 270)
			(size 0 0)
			(layers "F.Cu" "F.Mask" "F.Paste")
			(net "RST_CPU0_LVC1_R_N")
		)
		(pad "2" smd circle
			(at 0.40005 0 270)
			(size 0 0)
			(layers "F.Cu" "F.Mask" "F.Paste")
			(net "GND")
		)
	)
)
